# T6G (Grand Teton) — schematic netlist excerpt (pin names and nets, part order shuffled) for the footprints in the layout excerpt that follows; sources: Cadence DE-HDL packaged netlist, KiCad conversion of 04192023_DAF0TMB3IC0_F0TG_MB_C_brd_V02_OCP.brd

U240  74LVC2G08DP  EMPTY  pkg TSSOP8_0-65_3X3  page 143
  \1a\  = OCP_SFF_PRSNT0_R_N
  \1b\  = OCP_SFF_PRSNT1_R_N
  \2y\  = OCP_SFF_PRSNT23_R_N
  GND  = GND
  \2a\  = OCP_SFF_PRSNT2_R_N
  \2b\  = OCP_SFF_PRSNT3_R_N
  \1y\  = OCP_SFF_PRSNT01_R_N
  VCC  = P3V3_AUX

(kicad_pcb
	(version 20260206)
	(generator "pcbnew")
	(generator_version "10.0")
	(general
		(thickness 1.6)
		(legacy_teardrops no)
	)
	(paper "A4")
	(title_block
		(title "04192023_DAF0TMB3IC0_F0TG_MB_C_brd_V02_OCP.brd")
		(comment 1 "Grand Teton / footprints 3226-3227 of 8354")
	)
	(layers
		(0 "F.Cu" signal "TOP")
		(4 "In1.Cu" signal "GND")
		(6 "In2.Cu" signal "IN1")
		(8 "In3.Cu" signal "GND1")
		(10 "In4.Cu" signal "IN2")
		(12 "In5.Cu" signal "GND2")
		(14 "In6.Cu" signal "IN3")
		(16 "In7.Cu" signal "GND3")
		(18 "In8.Cu" signal "VCC")
		(20 "In9.Cu" signal "VCC1")
		(22 "In10.Cu" signal "GND4")
		(24 "In11.Cu" signal "IN4")
		(26 "In12.Cu" signal "GND5")
		(28 "In13.Cu" signal "IN5")
		(30 "In14.Cu" signal "GND6")
		(32 "In15.Cu" signal "IN6")
		(34 "In16.Cu" signal "GND7")
		(2 "B.Cu" signal "BOTTOM")
		(9 "F.Adhes" user "F.Adhesive")
		(11 "B.Adhes" user "B.Adhesive")
		(13 "F.Paste" user "Package Geometry/Pastemask Top")
		(15 "B.Paste" user "Package Geometry/Pastemask Bottom")
		(5 "F.SilkS" user "Ref Des/Silkscreen Top")
		(7 "B.SilkS" user "Ref Des/Silkscreen Bottom")
		(1 "F.Mask" user "Board Geometry/Soldermask Top")
		(3 "B.Mask" user "Board Geometry/Soldermask Bottom")
		(17 "Dwgs.User" user "User.Drawings")
		(19 "Cmts.User" user "User.Comments")
		(21 "Eco1.User" user "User.Eco1")
		(23 "Eco2.User" user "User.Eco2")
		(25 "Edge.Cuts" user "Board Geometry/Outline")
		(27 "Margin" user)
		(31 "F.CrtYd" user "Package Geometry/Place Bound Top")
		(29 "B.CrtYd" user "Package Geometry/Place Bound Bottom")
		(35 "F.Fab" user "Ref Des/Assembly Top")
		(33 "B.Fab" user "Ref Des/Assembly Bottom")
	)
	(footprint ""
		(layer "F.Cu")
		(at 366.114076 -75.652122)
		(property "Reference" "ME29"
			(at 0 0 0)
			(layer "F.SilkS")
			(hide yes)
			(effects
				(font
					(size 1.27 1.27)
				)
			)
		)
		(property "Value" ""
			(at 0 0 0)
			(layer "F.Fab")
			(effects
				(font
					(size 1.27 1.27)
				)
			)
		)
		(duplicate_pad_numbers_are_jumpers no)
		(fp_line
			(start 0 -4.99999)
			(end 0 -3.47599)
			(stroke
				(width 0.1524)
				(type default)
			)
			(layer "F.SilkS")
		)
		(fp_line
			(start 0 -1.524)
			(end 0 0)
			(stroke
				(width 0.1524)
				(type default)
			)
			(layer "F.SilkS")
		)
		(fp_line
			(start 0 0)
			(end 1.524 0)
			(stroke
				(width 0.1524)
				(type default)
			)
			(layer "F.SilkS")
		)
		(fp_line
			(start 1.524 -4.99999)
			(end 0 -4.99999)
			(stroke
				(width 0.1524)
				(type default)
			)
			(layer "F.SilkS")
		)
		(fp_line
			(start 13.47597 0)
			(end 14.99997 0)
			(stroke
				(width 0.1524)
				(type default)
			)
			(layer "F.SilkS")
		)
		(fp_line
			(start 14.99997 -4.99999)
			(end 13.47597 -4.99999)
			(stroke
				(width 0.1524)
				(type default)
			)
			(layer "F.SilkS")
		)
		(fp_line
			(start 14.99997 -3.47599)
			(end 14.99997 -4.99999)
			(stroke
				(width 0.1524)
				(type default)
			)
			(layer "F.SilkS")
		)
		(fp_line
			(start 14.99997 0)
			(end 14.99997 -1.524)
			(stroke
				(width 0.1524)
				(type default)
			)
			(layer "F.SilkS")
		)
		(fp_text user "S/N"
			(at 0.1016 -3.54965 0)
			(unlocked yes)
			(layer "F.SilkS")
			(effects
				(font
					(size 1.905 1.4224)
					(thickness 0.1524)
				)
				(justify left)
			)
		)
	)
	(footprint ""
		(layer "F.Cu")
		(at 416.51174 -57.372758)
		(property "Reference" "U240"
			(at -2.3876 -2.250948 0)
			(unlocked yes)
			(layer "F.SilkS")
			(effects
				(font
					(size 0.7874 0.5842)
					(thickness 0.1524)
				)
				(justify left)
			)
		)
		(property "Value" ""
			(at 0 0 0)
			(layer "F.Fab")
			(effects
				(font
					(size 1.27 1.27)
				)
			)
		)
		(duplicate_pad_numbers_are_jumpers no)
		(fp_line
			(start -1.207008 -1.549908)
			(end -1.207008 1.549908)
			(stroke
				(width 0.1524)
				(type default)
			)
			(layer "F.SilkS")
		)
		(fp_line
			(start -1.207008 1.549908)
			(end 1.207008 1.549908)
			(stroke
				(width 0.1524)
				(type default)
			)
			(layer "F.SilkS")
		)
		(fp_line
			(start -0.762508 -1.549908)
			(end -1.207008 -1.549908)
			(stroke
				(width 0.1524)
				(type default)
			)
			(layer "F.SilkS")
		)
		(fp_line
			(start 0 -0.635)
			(end -0.762508 -1.549908)
			(stroke
				(width 0.1524)
				(type default)
			)
			(layer "F.SilkS")
		)
		(fp_line
			(start 0.762508 -1.549908)
			(end 0 -0.635)
			(stroke
				(width 0.1524)
				(type default)
			)
			(layer "F.SilkS")
		)
		(fp_line
			(start 1.207008 -1.549908)
			(end 0.762508 -1.549908)
			(stroke
				(width 0.1524)
				(type default)
			)
			(layer "F.SilkS")
		)
		(fp_line
			(start 1.207008 1.549908)
			(end 1.207008 -1.549908)
			(stroke
				(width 0.1524)
				(type default)
			)
			(layer "F.SilkS")
		)
		(fp_poly
			(pts
				(xy -2.3876 -1.02489) (xy -3.4036 -0.51689) (xy -3.4036 -1.53289)
			)
			(stroke
				(width 0)
				(type default)
			)
			(fill yes)
			(layer "F.SilkS")
		)
		(fp_line
			(start -1.549908 -1.549908)
			(end -1.549908 1.549908)
			(stroke
				(width 0.1)
				(type default)
			)
			(layer "F.Fab")
		)
		(fp_line
			(start -1.549908 1.549908)
			(end 1.549908 1.549908)
			(stroke
				(width 0.1)
				(type default)
			)
			(layer "F.Fab")
		)
		(fp_line
			(start 1.549908 -1.549908)
			(end -1.549908 -1.549908)
			(stroke
				(width 0.1)
				(type default)
			)
			(layer "F.Fab")
		)
		(fp_line
			(start 1.549908 1.549908)
			(end 1.549908 -1.549908)
			(stroke
				(width 0.1)
				(type default)
			)
			(layer "F.Fab")
		)
		(fp_poly
			(pts
				(xy -3.4036 -1.53289) (xy -3.4036 -0.51689) (xy -2.3876 -1.02489)
			)
			(stroke
				(width 0)
				(type default)
			)
			(fill yes)
			(layer "F.Fab")
		)
		(pad "1" smd rect
			(at -1.774952 -1.02489 270)
			(size 0.508 0.8636)
			(layers "F.Cu" "F.Mask" "F.Paste")
			(net "OCP_SFF_PRSNT0_R_N")
		)
		(pad "2" smd rect
			(at -1.774952 -0.32512 270)
			(size 0.4064 0.8636)
			(layers "F.Cu" "F.Mask" "F.Paste")
			(net "OCP_SFF_PRSNT1_R_N")
		)
		(pad "3" smd rect
			(at -1.774952 0.32512 270)
			(size 0.4064 0.8636)
			(layers "F.Cu" "F.Mask" "F.Paste")
			(net "OCP_SFF_PRSNT23_R_N")
		)
		(pad "4" smd rect
			(at -1.774952 1.02489 270)
			(size 0.508 0.8636)
			(layers "F.Cu" "F.Mask" "F.Paste")
			(net "GND")
		)
		(pad "5" smd rect
			(at 1.774952 1.02489 270)
			(size 0.508 0.8636)
			(layers "F.Cu" "F.Mask" "F.Paste")
			(net "OCP_SFF_PRSNT2_R_N")
		)
		(pad "6" smd rect
			(at 1.774952 0.32512 270)
			(size 0.4064 0.8636)
			(layers "F.Cu" "F.Mask" "F.Paste")
			(net "OCP_SFF_PRSNT3_R_N")
		)
		(pad "7" smd rect
			(at 1.774952 -0.32512 270)
			(size 0.4064 0.8636)
			(layers "F.Cu" "F.Mask" "F.Paste")
			(net "OCP_SFF_PRSNT01_R_N")
		)
		(pad "8" smd rect
			(at 1.774952 -1.02489 270)
			(size 0.508 0.8636)
			(layers "F.Cu" "F.Mask" "F.Paste")
			(net "P3V3_AUX")
		)
	)
)
